# T6G (Grand Teton) — schematic netlist excerpt (pin names and nets, part order shuffled) for the footprints in the layout excerpt that follows; sources: Cadence DE-HDL packaged netlist, KiCad conversion of 04192023_DAF0TMB3IC0_F0TG_MB_C_brd_V02_OCP.brd

C6651  Q_CAP_DIFFBUS  DIFF BUS_0.22UF 6.3V 20% X6S  pkg C0201  page 319 : \1\ = P5E_CPU1_P0_TX_BUF_C_DP<11> ; \2\ = P5E_CPU1_P0_TX_BUF_DP<11>
R3651  Q_RES  0 5% CHIP  pkg 0402LF  page 234 : A = USB2_P0_R_DP ; B = USB2_HOST_BMC_B_DP
R1377  Q_RES  1K 1% EMPTY  pkg 0201LF  page 331 : A = P1V8_CPU1_RT_1D ; B = RXDET_BYP_RT_CPU1_P1

(kicad_pcb
	(version 20260206)
	(generator "pcbnew")
	(generator_version "10.0")
	(general
		(thickness 1.6)
		(legacy_teardrops no)
	)
	(paper "A4")
	(title_block
		(title "04192023_DAF0TMB3IC0_F0TG_MB_C_brd_V02_OCP.brd")
		(comment 1 "Grand Teton / footprints 1327-1329 of 8354")
	)
	(layers
		(0 "F.Cu" signal "TOP")
		(4 "In1.Cu" signal "GND")
		(6 "In2.Cu" signal "IN1")
		(8 "In3.Cu" signal "GND1")
		(10 "In4.Cu" signal "IN2")
		(12 "In5.Cu" signal "GND2")
		(14 "In6.Cu" signal "IN3")
		(16 "In7.Cu" signal "GND3")
		(18 "In8.Cu" signal "VCC")
		(20 "In9.Cu" signal "VCC1")
		(22 "In10.Cu" signal "GND4")
		(24 "In11.Cu" signal "IN4")
		(26 "In12.Cu" signal "GND5")
		(28 "In13.Cu" signal "IN5")
		(30 "In14.Cu" signal "GND6")
		(32 "In15.Cu" signal "IN6")
		(34 "In16.Cu" signal "GND7")
		(2 "B.Cu" signal "BOTTOM")
		(9 "F.Adhes" user "F.Adhesive")
		(11 "B.Adhes" user "B.Adhesive")
		(13 "F.Paste" user "Package Geometry/Pastemask Top")
		(15 "B.Paste" user "Package Geometry/Pastemask Bottom")
		(5 "F.SilkS" user "Ref Des/Silkscreen Top")
		(7 "B.SilkS" user "Ref Des/Silkscreen Bottom")
		(1 "F.Mask" user "Board Geometry/Soldermask Top")
		(3 "B.Mask" user "Board Geometry/Soldermask Bottom")
		(17 "Dwgs.User" user "User.Drawings")
		(19 "Cmts.User" user "User.Comments")
		(21 "Eco1.User" user "User.Eco1")
		(23 "Eco2.User" user "User.Eco2")
		(25 "Edge.Cuts" user "Board Geometry/Outline")
		(27 "Margin" user)
		(31 "F.CrtYd" user "Package Geometry/Place Bound Top")
		(29 "B.CrtYd" user "Package Geometry/Place Bound Bottom")
		(35 "F.Fab" user "Ref Des/Assembly Top")
		(33 "B.Fab" user "Ref Des/Assembly Bottom")
	)
	(footprint ""
		(layer "F.Cu")
		(at 82.378804 -408.517344 -90)
		(property "Reference" "C6651"
			(at 0 0 270)
			(layer "F.SilkS")
			(hide yes)
			(effects
				(font
					(size 1.27 1.27)
				)
			)
		)
		(property "Value" ""
			(at 0 0 270)
			(layer "F.Fab")
			(effects
				(font
					(size 1.27 1.27)
				)
			)
		)
		(duplicate_pad_numbers_are_jumpers no)
		(fp_line
			(start -0.299974 0.150114)
			(end -0.299974 -0.150114)
			(stroke
				(width 0.1)
				(type default)
			)
			(layer "F.Fab")
		)
		(fp_line
			(start 0.299974 0.150114)
			(end -0.299974 0.150114)
			(stroke
				(width 0.1)
				(type default)
			)
			(layer "F.Fab")
		)
		(fp_line
			(start -0.299974 -0.150114)
			(end 0.299974 -0.150114)
			(stroke
				(width 0.1)
				(type default)
			)
			(layer "F.Fab")
		)
		(fp_line
			(start 0.299974 -0.150114)
			(end 0.299974 0.150114)
			(stroke
				(width 0.1)
				(type default)
			)
			(layer "F.Fab")
		)
		(pad "1" smd rect
			(at -0.2667 0 270)
			(size 0.3048 0.381)
			(layers "F.Cu" "F.Mask" "F.Paste")
			(net "P5E_CPU1_P0_TX_BUF_C_DP<11>")
		)
		(pad "2" smd rect
			(at 0.2667 0 270)
			(size 0.3048 0.381)
			(layers "F.Cu" "F.Mask" "F.Paste")
			(net "P5E_CPU1_P0_TX_BUF_DP<11>")
		)
	)
	(footprint ""
		(layer "F.Cu")
		(at 15.288006 -104.73563 90)
		(property "Reference" "R3651"
			(at 0 0 90)
			(layer "F.SilkS")
			(hide yes)
			(effects
				(font
					(size 1.27 1.27)
				)
			)
		)
		(property "Value" ""
			(at 0 0 90)
			(layer "F.Fab")
			(effects
				(font
					(size 1.27 1.27)
				)
			)
		)
		(duplicate_pad_numbers_are_jumpers no)
		(fp_line
			(start 0.7874 -0.4064)
			(end 0.7874 0.4064)
			(stroke
				(width 0.1524)
				(type default)
			)
			(layer "F.SilkS")
		)
		(fp_line
			(start -0.7874 -0.4064)
			(end 0.7874 -0.4064)
			(stroke
				(width 0.1524)
				(type default)
			)
			(layer "F.SilkS")
		)
		(fp_line
			(start 0.7874 0.4064)
			(end -0.7874 0.4064)
			(stroke
				(width 0.1524)
				(type default)
			)
			(layer "F.SilkS")
		)
		(fp_line
			(start -0.7874 0.4064)
			(end -0.7874 -0.4064)
			(stroke
				(width 0.1524)
				(type default)
			)
			(layer "F.SilkS")
		)
		(fp_line
			(start -0.12065 -0.305054)
			(end -0.12065 -0.2794)
			(stroke
				(width 0.1)
				(type default)
			)
			(layer "F.Fab")
		)
		(fp_line
			(start -0.67945 -0.305054)
			(end -0.12065 -0.305054)
			(stroke
				(width 0.1)
				(type default)
			)
			(layer "F.Fab")
		)
		(fp_line
			(start 0.67945 -0.3048)
			(end 0.67945 0.3048)
			(stroke
				(width 0.1)
				(type default)
			)
			(layer "F.Fab")
		)
		(fp_line
			(start 0.12065 -0.3048)
			(end 0.67945 -0.3048)
			(stroke
				(width 0.1)
				(type default)
			)
			(layer "F.Fab")
		)
		(fp_line
			(start 0.12065 -0.2794)
			(end 0.12065 -0.3048)
			(stroke
				(width 0.1)
				(type default)
			)
			(layer "F.Fab")
		)
		(fp_line
			(start -0.12065 -0.2794)
			(end 0.12065 -0.2794)
			(stroke
				(width 0.1)
				(type default)
			)
			(layer "F.Fab")
		)
		(fp_line
			(start 0.120396 0.2794)
			(end -0.12065 0.2794)
			(stroke
				(width 0.1)
				(type default)
			)
			(layer "F.Fab")
		)
		(fp_line
			(start -0.12065 0.2794)
			(end -0.12065 0.3048)
			(stroke
				(width 0.1)
				(type default)
			)
			(layer "F.Fab")
		)
		(fp_line
			(start 0.67945 0.3048)
			(end 0.120396 0.3048)
			(stroke
				(width 0.1)
				(type default)
			)
			(layer "F.Fab")
		)
		(fp_line
			(start 0.120396 0.3048)
			(end 0.120396 0.2794)
			(stroke
				(width 0.1)
				(type default)
			)
			(layer "F.Fab")
		)
		(fp_line
			(start -0.12065 0.3048)
			(end -0.67945 0.3048)
			(stroke
				(width 0.1)
				(type default)
			)
			(layer "F.Fab")
		)
		(fp_line
			(start -0.67945 0.3048)
			(end -0.67945 -0.305054)
			(stroke
				(width 0.1)
				(type default)
			)
			(layer "F.Fab")
		)
		(pad "1" smd rect
			(at -0.40005 0 270)
			(size 0.4572 0.508)
			(layers "F.Cu" "F.Mask" "F.Paste")
			(net "USB2_P0_R_DP")
		)
		(pad "2" smd rect
			(at 0.40005 0 270)
			(size 0.4572 0.508)
			(layers "F.Cu" "F.Mask" "F.Paste")
			(net "USB2_HOST_BMC_B_DP")
		)
	)
	(footprint ""
		(layer "F.Cu")
		(at 104.1908 -390.652)
		(property "Reference" "R1377"
			(at 0 0 0)
			(layer "F.SilkS")
			(hide yes)
			(effects
				(font
					(size 1.27 1.27)
				)
			)
		)
		(property "Value" ""
			(at 0 0 0)
			(layer "F.Fab")
			(effects
				(font
					(size 1.27 1.27)
				)
			)
		)
		(duplicate_pad_numbers_are_jumpers no)
		(fp_line
			(start -0.32512 -0.175006)
			(end 0.32512 -0.175006)
			(stroke
				(width 0.1)
				(type default)
			)
			(layer "F.Fab")
		)
		(fp_line
			(start -0.32512 0.175006)
			(end -0.32512 -0.175006)
			(stroke
				(width 0.1)
				(type default)
			)
			(layer "F.Fab")
		)
		(fp_line
			(start 0.32512 -0.175006)
			(end 0.32512 0.175006)
			(stroke
				(width 0.1)
				(type default)
			)
			(layer "F.Fab")
		)
		(fp_line
			(start 0.32512 0.175006)
			(end -0.32512 0.175006)
			(stroke
				(width 0.1)
				(type default)
			)
			(layer "F.Fab")
		)
		(pad "1" smd rect
			(at -0.2667 0)
			(size 0.3048 0.381)
			(layers "F.Cu" "F.Mask" "F.Paste")
			(net "P1V8_CPU1_RT_1D")
		)
		(pad "2" smd rect
			(at 0.2667 0 180)
			(size 0.3048 0.381)
			(layers "F.Cu" "F.Mask" "F.Paste")
			(net "RXDET_BYP_RT_CPU1_P1")
		)
	)
)
